(kicad_pcb
	(version 20260206)
	(generator "pcbnew")
	(generator_version "10.0")
	(general
		(thickness 1.6)
		(legacy_teardrops no)
	)
	(paper "A4")
	(title_block
		(title "01162023_DA0F0TEBIF0_F0T_Expander_BD_F_brd_V02_OCP.brd")
		(comment 1 "Grand Teton / footprints 4911-4919 of 9728")
	)
	(layers
		(0 "F.Cu" signal "TOP")
		(4 "In1.Cu" signal "GND")
		(6 "In2.Cu" signal "VCC")
		(8 "In3.Cu" signal "VCC1")
		(10 "In4.Cu" signal "GND1")
		(12 "In5.Cu" signal "IN1")
		(14 "In6.Cu" signal "GND2")
		(16 "In7.Cu" signal "IN2")
		(18 "In8.Cu" signal "GND3")
		(20 "In9.Cu" signal "IN3")
		(22 "In10.Cu" signal "GND4")
		(24 "In11.Cu" signal "IN4")
		(26 "In12.Cu" signal "GND5")
		(28 "In13.Cu" signal "IN5")
		(30 "In14.Cu" signal "GND6")
		(32 "In15.Cu" signal "IN6")
		(34 "In16.Cu" signal "GND7")
		(2 "B.Cu" signal "BOTTOM")
		(9 "F.Adhes" user "F.Adhesive")
		(11 "B.Adhes" user "B.Adhesive")
		(13 "F.Paste" user "Package Geometry/Pastemask Top")
		(15 "B.Paste" user "Package Geometry/Pastemask Bottom")
		(5 "F.SilkS" user "Ref Des/Silkscreen Top")
		(7 "B.SilkS" user "Ref Des/Silkscreen Bottom")
		(1 "F.Mask" user "Board Geometry/Soldermask Top")
		(3 "B.Mask" user "Board Geometry/Soldermask Bottom")
		(17 "Dwgs.User" user "User.Drawings")
		(19 "Cmts.User" user "User.Comments")
		(21 "Eco1.User" user "User.Eco1")
		(23 "Eco2.User" user "User.Eco2")
		(25 "Edge.Cuts" user "Board Geometry/Outline")
		(27 "Margin" user)
		(31 "F.CrtYd" user "Package Geometry/Place Bound Top")
		(29 "B.CrtYd" user "Package Geometry/Place Bound Bottom")
		(35 "F.Fab" user "Ref Des/Assembly Top")
		(33 "B.Fab" user "Ref Des/Assembly Bottom")
	)
	(footprint ""
		(layer "F.Cu")
		(at 106.29265 -9.139682 180)
		(property "Reference" "C2717"
			(at 0 0 180)
			(layer "F.SilkS")
			(hide yes)
			(effects
				(font
					(size 1.27 1.27)
				)
			)
		)
		(property "Value" ""
			(at 0 0 180)
			(layer "F.Fab")
			(effects
				(font
					(size 1.27 1.27)
				)
			)
		)
		(duplicate_pad_numbers_are_jumpers no)
		(fp_line
			(start 0.7874 0.4064)
			(end -0.7874 0.4064)
			(stroke
				(width 0.1524)
				(type default)
			)
			(layer "F.SilkS")
		)
		(fp_line
			(start 0.7874 -0.4064)
			(end 0.7874 0.4064)
			(stroke
				(width 0.1524)
				(type default)
			)
			(layer "F.SilkS")
		)
		(fp_line
			(start -0.7874 0.4064)
			(end -0.7874 -0.4064)
			(stroke
				(width 0.1524)
				(type default)
			)
			(layer "F.SilkS")
		)
		(fp_line
			(start -0.7874 -0.4064)
			(end 0.7874 -0.4064)
			(stroke
				(width 0.1524)
				(type default)
			)
			(layer "F.SilkS")
		)
		(fp_line
			(start 0.67945 0.3048)
			(end 0.120396 0.3048)
			(stroke
				(width 0.1)
				(type default)
			)
			(layer "F.Fab")
		)
		(fp_line
			(start 0.67945 -0.3048)
			(end 0.67945 0.3048)
			(stroke
				(width 0.1)
				(type default)
			)
			(layer "F.Fab")
		)
		(fp_line
			(start 0.12065 -0.2794)
			(end 0.12065 -0.3048)
			(stroke
				(width 0.1)
				(type default)
			)
			(layer "F.Fab")
		)
		(fp_line
			(start 0.12065 -0.3048)
			(end 0.67945 -0.3048)
			(stroke
				(width 0.1)
				(type default)
			)
			(layer "F.Fab")
		)
		(fp_line
			(start 0.120396 0.3048)
			(end 0.120396 0.2794)
			(stroke
				(width 0.1)
				(type default)
			)
			(layer "F.Fab")
		)
		(fp_line
			(start 0.120396 0.2794)
			(end -0.12065 0.2794)
			(stroke
				(width 0.1)
				(type default)
			)
			(layer "F.Fab")
		)
		(fp_line
			(start -0.12065 0.3048)
			(end -0.67945 0.3048)
			(stroke
				(width 0.1)
				(type default)
			)
			(layer "F.Fab")
		)
		(fp_line
			(start -0.12065 0.2794)
			(end -0.12065 0.3048)
			(stroke
				(width 0.1)
				(type default)
			)
			(layer "F.Fab")
		)
		(fp_line
			(start -0.12065 -0.2794)
			(end 0.12065 -0.2794)
			(stroke
				(width 0.1)
				(type default)
			)
			(layer "F.Fab")
		)
		(fp_line
			(start -0.12065 -0.305054)
			(end -0.12065 -0.2794)
			(stroke
				(width 0.1)
				(type default)
			)
			(layer "F.Fab")
		)
		(fp_line
			(start -0.67945 0.3048)
			(end -0.67945 -0.305054)
			(stroke
				(width 0.1)
				(type default)
			)
			(layer "F.Fab")
		)
		(fp_line
			(start -0.67945 -0.305054)
			(end -0.12065 -0.305054)
			(stroke
				(width 0.1)
				(type default)
			)
			(layer "F.Fab")
		)
		(pad "1" smd circle
			(at -0.40005 0 180)
			(size 0 0)
			(layers "F.Cu" "F.Mask" "F.Paste")
			(net "GND")
		)
		(pad "2" smd circle
			(at 0.40005 0 180)
			(size 0 0)
			(layers "F.Cu" "F.Mask" "F.Paste")
			(net "P3V3_AUX")
		)
	)
	(footprint ""
		(layer "F.Cu")
		(at 207.268826 -121.797318 90)
		(property "Reference" "PC489"
			(at 0 0 90)
			(layer "F.SilkS")
			(hide yes)
			(effects
				(font
					(size 1.27 1.27)
				)
			)
		)
		(property "Value" ""
			(at 0 0 90)
			(layer "F.Fab")
			(effects
				(font
					(size 1.27 1.27)
				)
			)
		)
		(duplicate_pad_numbers_are_jumpers no)
		(fp_line
			(start 1.524 -0.762)
			(end 1.524 0.762)
			(stroke
				(width 0.1524)
				(type default)
			)
			(layer "F.SilkS")
		)
		(fp_line
			(start -1.524 -0.762)
			(end 1.524 -0.762)
			(stroke
				(width 0.1524)
				(type default)
			)
			(layer "F.SilkS")
		)
		(fp_line
			(start 1.524 0.762)
			(end -1.524 0.762)
			(stroke
				(width 0.1524)
				(type default)
			)
			(layer "F.SilkS")
		)
		(fp_line
			(start -1.524 0.762)
			(end -1.524 -0.762)
			(stroke
				(width 0.1524)
				(type default)
			)
			(layer "F.SilkS")
		)
		(fp_line
			(start 1.1049 -0.724916)
			(end -1.1049 -0.724916)
			(stroke
				(width 0.1)
				(type default)
			)
			(layer "F.Fab")
		)
		(fp_line
			(start -1.1049 -0.724916)
			(end -1.1049 0.724916)
			(stroke
				(width 0.1)
				(type default)
			)
			(layer "F.Fab")
		)
		(fp_line
			(start 1.1049 0.724916)
			(end 1.1049 -0.724916)
			(stroke
				(width 0.1)
				(type default)
			)
			(layer "F.Fab")
		)
		(fp_line
			(start -1.1049 0.724916)
			(end 1.1049 0.724916)
			(stroke
				(width 0.1)
				(type default)
			)
			(layer "F.Fab")
		)
		(pad "1" smd rect
			(at -0.889 0 270)
			(size 1.016 1.27)
			(layers "F.Cu" "F.Mask" "F.Paste")
			(net "P3V3_NIC3")
		)
		(pad "2" smd rect
			(at 0.889 0 270)
			(size 1.016 1.27)
			(layers "F.Cu" "F.Mask" "F.Paste")
			(net "GND")
		)
	)
	(footprint ""
		(layer "F.Cu")
		(at 115.358926 -264.95756 180)
		(property "Reference" "PR7133"
			(at 0 0 180)
			(layer "F.SilkS")
			(hide yes)
			(effects
				(font
					(size 1.27 1.27)
				)
			)
		)
		(property "Value" ""
			(at 0 0 180)
			(layer "F.Fab")
			(effects
				(font
					(size 1.27 1.27)
				)
			)
		)
		(duplicate_pad_numbers_are_jumpers no)
		(fp_line
			(start 0.7874 0.4064)
			(end -0.7874 0.4064)
			(stroke
				(width 0.1524)
				(type default)
			)
			(layer "F.SilkS")
		)
		(fp_line
			(start 0.7874 -0.4064)
			(end 0.7874 0.4064)
			(stroke
				(width 0.1524)
				(type default)
			)
			(layer "F.SilkS")
		)
		(fp_line
			(start -0.7874 0.4064)
			(end -0.7874 -0.4064)
			(stroke
				(width 0.1524)
				(type default)
			)
			(layer "F.SilkS")
		)
		(fp_line
			(start -0.7874 -0.4064)
			(end 0.7874 -0.4064)
			(stroke
				(width 0.1524)
				(type default)
			)
			(layer "F.SilkS")
		)
		(fp_line
			(start 0.67945 0.3048)
			(end 0.120396 0.3048)
			(stroke
				(width 0.1)
				(type default)
			)
			(layer "F.Fab")
		)
		(fp_line
			(start 0.67945 -0.3048)
			(end 0.67945 0.3048)
			(stroke
				(width 0.1)
				(type default)
			)
			(layer "F.Fab")
		)
		(fp_line
			(start 0.12065 -0.2794)
			(end 0.12065 -0.3048)
			(stroke
				(width 0.1)
				(type default)
			)
			(layer "F.Fab")
		)
		(fp_line
			(start 0.12065 -0.3048)
			(end 0.67945 -0.3048)
			(stroke
				(width 0.1)
				(type default)
			)
			(layer "F.Fab")
		)
		(fp_line
			(start 0.120396 0.3048)
			(end 0.120396 0.2794)
			(stroke
				(width 0.1)
				(type default)
			)
			(layer "F.Fab")
		)
		(fp_line
			(start 0.120396 0.2794)
			(end -0.12065 0.2794)
			(stroke
				(width 0.1)
				(type default)
			)
			(layer "F.Fab")
		)
		(fp_line
			(start -0.12065 0.3048)
			(end -0.67945 0.3048)
			(stroke
				(width 0.1)
				(type default)
			)
			(layer "F.Fab")
		)
		(fp_line
			(start -0.12065 0.2794)
			(end -0.12065 0.3048)
			(stroke
				(width 0.1)
				(type default)
			)
			(layer "F.Fab")
		)
		(fp_line
			(start -0.12065 -0.2794)
			(end 0.12065 -0.2794)
			(stroke
				(width 0.1)
				(type default)
			)
			(layer "F.Fab")
		)
		(fp_line
			(start -0.12065 -0.305054)
			(end -0.12065 -0.2794)
			(stroke
				(width 0.1)
				(type default)
			)
			(layer "F.Fab")
		)
		(fp_line
			(start -0.67945 0.3048)
			(end -0.67945 -0.305054)
			(stroke
				(width 0.1)
				(type default)
			)
			(layer "F.Fab")
		)
		(fp_line
			(start -0.67945 -0.305054)
			(end -0.12065 -0.305054)
			(stroke
				(width 0.1)
				(type default)
			)
			(layer "F.Fab")
		)
		(pad "1" smd circle
			(at -0.40005 0 180)
			(size 0 0)
			(layers "F.Cu" "F.Mask" "F.Paste")
			(net "NC_P0V8_PEX0_ISEN4")
		)
		(pad "2" smd circle
			(at 0.40005 0 180)
			(size 0 0)
			(layers "F.Cu" "F.Mask" "F.Paste")
			(net "GND")
		)
	)
	(footprint ""
		(layer "F.Cu")
		(at 215.758014 -347.400118 90)
		(property "Reference" "H143"
			(at -4.11861 2.428494 0)
			(unlocked yes)
			(layer "F.SilkS")
			(effects
				(font
					(size 0.7874 0.5842)
					(thickness 0.1524)
				)
				(justify left)
			)
		)
		(property "Value" ""
			(at 0 0 90)
			(layer "F.Fab")
			(effects
				(font
					(size 1.27 1.27)
				)
			)
		)
		(duplicate_pad_numbers_are_jumpers no)
		(pad "1" thru_hole circle
			(at 0 0 90)
			(size 8.001 8.001)
			(drill 4.2164)
			(layers "*.Cu" "*.Mask")
			(remove_unused_layers no)
			(net "GND")
			(clearance -1.6383)
		)
	)
	(footprint ""
		(layer "F.Cu")
		(at 15.80007 -194.360038)
		(property "Reference" "H67"
			(at -4.464812 -5.059172 0)
			(unlocked yes)
			(layer "F.SilkS")
			(effects
				(font
					(size 0.7874 0.5842)
					(thickness 0.1524)
				)
				(justify left)
			)
		)
		(property "Value" ""
			(at 0 0 0)
			(layer "F.Fab")
			(effects
				(font
					(size 1.27 1.27)
				)
			)
		)
		(duplicate_pad_numbers_are_jumpers no)
		(pad "1" thru_hole circle
			(at 0 0)
			(size 10.0076 10.0076)
			(drill 5.6134)
			(layers "*.Cu" "*.Mask")
			(remove_unused_layers no)
			(net "GND")
			(clearance -1.9431)
		)
	)
	(footprint ""
		(layer "F.Cu")
		(at 389.442706 -70.844918 -90)
		(property "Reference" "PD119"
			(at 4.195318 2.142236 90)
			(unlocked yes)
			(layer "F.SilkS")
			(effects
				(font
					(size 0.7874 0.5842)
					(thickness 0.1524)
				)
				(justify left)
			)
		)
		(property "Value" ""
			(at 0 0 270)
			(layer "F.Fab")
			(effects
				(font
					(size 1.27 1.27)
				)
			)
		)
		(duplicate_pad_numbers_are_jumpers no)
		(fp_line
			(start -3.400044 1.459992)
			(end -3.400044 -1.459992)
			(stroke
				(width 0.1524)
				(type default)
			)
			(layer "F.SilkS")
		)
		(fp_line
			(start 4.107942 1.459992)
			(end -3.400044 1.459992)
			(stroke
				(width 0.1524)
				(type default)
			)
			(layer "F.SilkS")
		)
		(fp_line
			(start -3.400044 -1.459992)
			(end 4.107942 -1.459992)
			(stroke
				(width 0.1524)
				(type default)
			)
			(layer "F.SilkS")
		)
		(fp_line
			(start 4.107942 -1.459992)
			(end 4.107942 1.459992)
			(stroke
				(width 0.1524)
				(type default)
			)
			(layer "F.SilkS")
		)
		(fp_poly
			(pts
				(xy 4.107942 -1.459992) (xy 4.107942 1.459992) (xy 3.308096 1.459992) (xy 3.308096 -1.459992)
			)
			(stroke
				(width 0)
				(type default)
			)
			(fill yes)
			(layer "F.SilkS")
		)
		(fp_line
			(start -2.29997 1.459992)
			(end -2.29997 -1.459992)
			(stroke
				(width 0.1)
				(type default)
			)
			(layer "F.Fab")
		)
		(fp_line
			(start 2.29997 1.459992)
			(end -2.29997 1.459992)
			(stroke
				(width 0.1)
				(type default)
			)
			(layer "F.Fab")
		)
		(fp_line
			(start -2.29997 -1.459992)
			(end 2.29997 -1.459992)
			(stroke
				(width 0.1)
				(type default)
			)
			(layer "F.Fab")
		)
		(fp_line
			(start 2.29997 -1.459992)
			(end 2.29997 1.459992)
			(stroke
				(width 0.1)
				(type default)
			)
			(layer "F.Fab")
		)
		(fp_text user "-"
			(at 5.4102 0.29845 90)
			(unlocked yes)
			(layer "F.SilkS")
			(effects
				(font
					(size 1.905 1.4224)
					(thickness 0.1524)
				)
				(justify left)
			)
		)
		(fp_text user "+"
			(at -5.38099 0.057404 270)
			(unlocked yes)
			(layer "F.SilkS")
			(effects
				(font
					(size 1.905 1.4224)
					(thickness 0.1524)
				)
				(justify left)
			)
		)
		(fp_text user "-"
			(at 5.4102 0.29845 90)
			(unlocked yes)
			(layer "F.Fab")
			(effects
				(font
					(size 1.905 1.4224)
					(thickness 0.1524)
				)
				(justify left)
			)
		)
		(fp_text user "+"
			(at -4.7752 -0.12065 270)
			(unlocked yes)
			(layer "F.Fab")
			(effects
				(font
					(size 1.905 1.4224)
					(thickness 0.1524)
				)
				(justify left)
			)
		)
		(pad "A" smd rect
			(at -1.999996 0)
			(size 1.7018 2.5146)
			(layers "F.Cu" "F.Mask" "F.Paste")
			(net "GND")
		)
		(pad "C" smd rect
			(at 1.999996 0)
			(size 1.7018 2.5146)
			(layers "F.Cu" "F.Mask" "F.Paste")
			(net "P12V_SSD13_R")
		)
	)
	(footprint ""
		(layer "F.Cu")
		(at 461.728312 -264.5537)
		(property "Reference" "C4407"
			(at 0 0 0)
			(layer "F.SilkS")
			(hide yes)
			(effects
				(font
					(size 1.27 1.27)
				)
			)
		)
		(property "Value" ""
			(at 0 0 0)
			(layer "F.Fab")
			(effects
				(font
					(size 1.27 1.27)
				)
			)
		)
		(duplicate_pad_numbers_are_jumpers no)
		(fp_line
			(start -0.299974 -0.150114)
			(end 0.299974 -0.150114)
			(stroke
				(width 0.1)
				(type default)
			)
			(layer "F.Fab")
		)
		(fp_line
			(start -0.299974 0.150114)
			(end -0.299974 -0.150114)
			(stroke
				(width 0.1)
				(type default)
			)
			(layer "F.Fab")
		)
		(fp_line
			(start 0.299974 -0.150114)
			(end 0.299974 0.150114)
			(stroke
				(width 0.1)
				(type default)
			)
			(layer "F.Fab")
		)
		(fp_line
			(start 0.299974 0.150114)
			(end -0.299974 0.150114)
			(stroke
				(width 0.1)
				(type default)
			)
			(layer "F.Fab")
		)
		(pad "1" smd rect
			(at -0.2667 0)
			(size 0.3048 0.381)
			(layers "F.Cu" "F.Mask" "F.Paste")
			(net "P1V25_SERDES_VDDPLL_PEX3")
		)
		(pad "2" smd rect
			(at 0.2667 0)
			(size 0.3048 0.381)
			(layers "F.Cu" "F.Mask" "F.Paste")
			(net "GND")
		)
	)
	(footprint ""
		(layer "F.Cu")
		(at 358.013 -227.584 180)
		(property "Reference" "R3616"
			(at 0 0 180)
			(layer "F.SilkS")
			(hide yes)
			(effects
				(font
					(size 1.27 1.27)
				)
			)
		)
		(property "Value" ""
			(at 0 0 180)
			(layer "F.Fab")
			(effects
				(font
					(size 1.27 1.27)
				)
			)
		)
		(duplicate_pad_numbers_are_jumpers no)
		(fp_line
			(start 0.7874 0.4064)
			(end -0.7874 0.4064)
			(stroke
				(width 0.1524)
				(type default)
			)
			(layer "F.SilkS")
		)
		(fp_line
			(start 0.7874 -0.4064)
			(end 0.7874 0.4064)
			(stroke
				(width 0.1524)
				(type default)
			)
			(layer "F.SilkS")
		)
		(fp_line
			(start -0.7874 0.4064)
			(end -0.7874 -0.4064)
			(stroke
				(width 0.1524)
				(type default)
			)
			(layer "F.SilkS")
		)
		(fp_line
			(start -0.7874 -0.4064)
			(end 0.7874 -0.4064)
			(stroke
				(width 0.1524)
				(type default)
			)
			(layer "F.SilkS")
		)
		(fp_line
			(start 0.67945 0.3048)
			(end 0.120396 0.3048)
			(stroke
				(width 0.1)
				(type default)
			)
			(layer "F.Fab")
		)
		(fp_line
			(start 0.67945 -0.3048)
			(end 0.67945 0.3048)
			(stroke
				(width 0.1)
				(type default)
			)
			(layer "F.Fab")
		)
		(fp_line
			(start 0.12065 -0.2794)
			(end 0.12065 -0.3048)
			(stroke
				(width 0.1)
				(type default)
			)
			(layer "F.Fab")
		)
		(fp_line
			(start 0.12065 -0.3048)
			(end 0.67945 -0.3048)
			(stroke
				(width 0.1)
				(type default)
			)
			(layer "F.Fab")
		)
		(fp_line
			(start 0.120396 0.3048)
			(end 0.120396 0.2794)
			(stroke
				(width 0.1)
				(type default)
			)
			(layer "F.Fab")
		)
		(fp_line
			(start 0.120396 0.2794)
			(end -0.12065 0.2794)
			(stroke
				(width 0.1)
				(type default)
			)
			(layer "F.Fab")
		)
		(fp_line
			(start -0.12065 0.3048)
			(end -0.67945 0.3048)
			(stroke
				(width 0.1)
				(type default)
			)
			(layer "F.Fab")
		)
		(fp_line
			(start -0.12065 0.2794)
			(end -0.12065 0.3048)
			(stroke
				(width 0.1)
				(type default)
			)
			(layer "F.Fab")
		)
		(fp_line
			(start -0.12065 -0.2794)
			(end 0.12065 -0.2794)
			(stroke
				(width 0.1)
				(type default)
			)
			(layer "F.Fab")
		)
		(fp_line
			(start -0.12065 -0.305054)
			(end -0.12065 -0.2794)
			(stroke
				(width 0.1)
				(type default)
			)
			(layer "F.Fab")
		)
		(fp_line
			(start -0.67945 0.3048)
			(end -0.67945 -0.305054)
			(stroke
				(width 0.1)
				(type default)
			)
			(layer "F.Fab")
		)
		(fp_line
			(start -0.67945 -0.305054)
			(end -0.12065 -0.305054)
			(stroke
				(width 0.1)
				(type default)
			)
			(layer "F.Fab")
		)
		(pad "1" smd circle
			(at -0.40005 0 180)
			(size 0 0)
			(layers "F.Cu" "F.Mask" "F.Paste")
			(net "NIC1_CLK_EN_R_N")
		)
		(pad "2" smd circle
			(at 0.40005 0 180)
			(size 0 0)
			(layers "F.Cu" "F.Mask" "F.Paste")
			(net "NIC1_CLK_EN_N")
		)
	)
	(footprint ""
		(layer "F.Cu")
		(at 16.785336 -274.232624)
		(property "Reference" "R774"
			(at 0 0 0)
			(layer "F.SilkS")
			(hide yes)
			(effects
				(font
					(size 1.27 1.27)
				)
			)
		)
		(property "Value" ""
			(at 0 0 0)
			(layer "F.Fab")
			(effects
				(font
					(size 1.27 1.27)
				)
			)
		)
		(duplicate_pad_numbers_are_jumpers no)
		(fp_line
			(start -0.7874 -0.4064)
			(end 0.7874 -0.4064)
			(stroke
				(width 0.1524)
				(type default)
			)
			(layer "F.SilkS")
		)
		(fp_line
			(start -0.7874 0.4064)
			(end -0.7874 -0.4064)
			(stroke
				(width 0.1524)
				(type default)
			)
			(layer "F.SilkS")
		)
		(fp_line
			(start 0.7874 -0.4064)
			(end 0.7874 0.4064)
			(stroke
				(width 0.1524)
				(type default)
			)
			(layer "F.SilkS")
		)
		(fp_line
			(start 0.7874 0.4064)
			(end -0.7874 0.4064)
			(stroke
				(width 0.1524)
				(type default)
			)
			(layer "F.SilkS")
		)
		(fp_line
			(start -0.67945 -0.305054)
			(end -0.12065 -0.305054)
			(stroke
				(width 0.1)
				(type default)
			)
			(layer "F.Fab")
		)
		(fp_line
			(start -0.67945 0.3048)
			(end -0.67945 -0.305054)
			(stroke
				(width 0.1)
				(type default)
			)
			(layer "F.Fab")
		)
		(fp_line
			(start -0.12065 -0.305054)
			(end -0.12065 -0.2794)
			(stroke
				(width 0.1)
				(type default)
			)
			(layer "F.Fab")
		)
		(fp_line
			(start -0.12065 -0.2794)
			(end 0.12065 -0.2794)
			(stroke
				(width 0.1)
				(type default)
			)
			(layer "F.Fab")
		)
		(fp_line
			(start -0.12065 0.2794)
			(end -0.12065 0.3048)
			(stroke
				(width 0.1)
				(type default)
			)
			(layer "F.Fab")
		)
		(fp_line
			(start -0.12065 0.3048)
			(end -0.67945 0.3048)
			(stroke
				(width 0.1)
				(type default)
			)
			(layer "F.Fab")
		)
		(fp_line
			(start 0.120396 0.2794)
			(end -0.12065 0.2794)
			(stroke
				(width 0.1)
				(type default)
			)
			(layer "F.Fab")
		)
		(fp_line
			(start 0.120396 0.3048)
			(end 0.120396 0.2794)
			(stroke
				(width 0.1)
				(type default)
			)
			(layer "F.Fab")
		)
		(fp_line
			(start 0.12065 -0.3048)
			(end 0.67945 -0.3048)
			(stroke
				(width 0.1)
				(type default)
			)
			(layer "F.Fab")
		)
		(fp_line
			(start 0.12065 -0.2794)
			(end 0.12065 -0.3048)
			(stroke
				(width 0.1)
				(type default)
			)
			(layer "F.Fab")
		)
		(fp_line
			(start 0.67945 -0.3048)
			(end 0.67945 0.3048)
			(stroke
				(width 0.1)
				(type default)
			)
			(layer "F.Fab")
		)
		(fp_line
			(start 0.67945 0.3048)
			(end 0.120396 0.3048)
			(stroke
				(width 0.1)
				(type default)
			)
			(layer "F.Fab")
		)
		(pad "1" smd circle
			(at -0.40005 0)
			(size 0 0)
			(layers "F.Cu" "F.Mask" "F.Paste")
			(net "PEX0_P1V25_ADC_A0")
		)
		(pad "2" smd circle
			(at 0.40005 0)
			(size 0 0)
			(layers "F.Cu" "F.Mask" "F.Paste")
			(net "GND")
		)
	)
)
